# BASEBOARD_FAB2 (Tioga Pass) — schematic netlist excerpt (pin names and nets, part order shuffled) for the footprints in the layout excerpt that follows; sources: Cadence DE-HDL packaged netlist, KiCad conversion of Wiwynn_Tioga_Pass_MB.brd

C6B3  CAP  47UF 4V 20% X6S  pkg 0805  page 232 : A = PVPP_DEF ; B = GND
C1B2  CAP_A  0.1UF 16V 10% X7R  pkg 0402V  page 226 : A = VR_PVDDQ_KLM_VD12 ; B = GND
C1C11  CAP  220PF 50V 10% X7R  pkg 0402LF  page 206 : A = A_TSENSE_PVSA_CPU1 ; B = GND

(kicad_pcb
	(version 20260206)
	(generator "pcbnew")
	(generator_version "10.0")
	(general
		(thickness 1.6)
		(legacy_teardrops no)
	)
	(paper "A4")
	(title_block
		(title "Wiwynn_Tioga_Pass_MB.brd")
		(comment 1 "Tioga Pass / footprints 2321-2323 of 4770")
	)
	(layers
		(0 "F.Cu" signal "TOP")
		(4 "In1.Cu" signal "L2GND")
		(6 "In2.Cu" signal "L3")
		(8 "In3.Cu" signal "L4GND")
		(10 "In4.Cu" signal "L5")
		(12 "In5.Cu" signal "L6GND")
		(14 "In6.Cu" signal "L7VCC")
		(16 "In7.Cu" signal "L8VCC")
		(18 "In8.Cu" signal "L9GND")
		(20 "In9.Cu" signal "L10")
		(22 "In10.Cu" signal "L11GND")
		(24 "In11.Cu" signal "L12")
		(26 "In12.Cu" signal "L13GND")
		(2 "B.Cu" signal "BOTTOM")
		(9 "F.Adhes" user "F.Adhesive")
		(11 "B.Adhes" user "B.Adhesive")
		(13 "F.Paste" user "Package Geometry/Pastemask Top")
		(15 "B.Paste" user "Package Geometry/Pastemask Bottom")
		(5 "F.SilkS" user "Ref Des/Silkscreen Top")
		(7 "B.SilkS" user "Ref Des/Silkscreen Bottom")
		(1 "F.Mask" user "Board Geometry/Soldermask Top")
		(3 "B.Mask" user "Board Geometry/Soldermask Bottom")
		(17 "Dwgs.User" user "User.Drawings")
		(19 "Cmts.User" user "User.Comments")
		(21 "Eco1.User" user "User.Eco1")
		(23 "Eco2.User" user "User.Eco2")
		(25 "Edge.Cuts" user "Board Geometry/Outline")
		(27 "Margin" user)
		(31 "F.CrtYd" user "Package Geometry/Place Bound Top")
		(29 "B.CrtYd" user "Package Geometry/Place Bound Bottom")
		(35 "F.Fab" user "Ref Des/Assembly Top")
		(33 "B.Fab" user "Ref Des/Assembly Bottom")
	)
	(footprint ""
		(layer "F.Cu")
		(at 4.31546 -132.49402 180)
		(property "Reference" "C1B2"
			(at -0.8382 -0.67818 180)
			(unlocked yes)
			(layer "F.SilkS")
			(effects
				(font
					(size 0.4064 0.254)
					(thickness 0.1524)
				)
				(justify left)
			)
		)
		(property "Value" ""
			(at 0 0 180)
			(layer "F.Fab")
			(effects
				(font
					(size 1.27 1.27)
				)
			)
		)
		(duplicate_pad_numbers_are_jumpers no)
		(fp_poly
			(pts
				(xy 0.3048 -0.1016) (xy 0.3048 0.9906) (xy -0.3048 0.9906) (xy -0.3048 -0.1016)
			)
			(stroke
				(width 0)
				(type default)
			)
			(fill no)
			(layer "F.CrtYd")
		)
		(fp_line
			(start 0.3048 0.9906)
			(end 0.3048 -0.1016)
			(stroke
				(width 0.1)
				(type default)
			)
			(layer "F.Fab")
		)
		(fp_line
			(start 0.3048 -0.1016)
			(end -0.3048 -0.1016)
			(stroke
				(width 0.1)
				(type default)
			)
			(layer "F.Fab")
		)
		(fp_line
			(start -0.3048 0.9906)
			(end 0.3048 0.9906)
			(stroke
				(width 0.1)
				(type default)
			)
			(layer "F.Fab")
		)
		(fp_line
			(start -0.3048 -0.1016)
			(end -0.3048 0.9906)
			(stroke
				(width 0.1)
				(type default)
			)
			(layer "F.Fab")
		)
		(pad "1" smd rect
			(at 0 0 180)
			(size 0.508 0.508)
			(layers "F.Cu" "F.Mask" "F.Paste")
			(net "VR_PVDDQ_KLM_VD12")
		)
		(pad "2" smd rect
			(at 0 0.889 180)
			(size 0.508 0.508)
			(layers "F.Cu" "F.Mask" "F.Paste")
			(net "GND")
		)
		(zone
			(layer "F.Cu")
			(hatch none 0.5)
			(connect_pads
				(clearance 0)
			)
			(min_thickness 0.25)
			(keepout
				(tracks not_allowed)
				(vias allowed)
				(pads allowed)
				(copperpour not_allowed)
				(footprints allowed)
			)
			(placement
				(enabled no)
				(sheetname "")
			)
			(fill
				(thermal_gap 0.5)
				(thermal_bridge_width 0.5)
				(island_removal_mode 0)
			)
			(polygon
				(pts
					(xy 4.56946 -133.12902) (xy 4.06146 -133.12902) (xy 4.06146 -132.74802) (xy 4.56946 -132.74802)
				)
			)
		)
		(zone
			(layer "F.Cu")
			(hatch none 0.5)
			(connect_pads
				(clearance 0)
			)
			(min_thickness 0.25)
			(keepout
				(tracks allowed)
				(vias not_allowed)
				(pads allowed)
				(copperpour not_allowed)
				(footprints allowed)
			)
			(placement
				(enabled no)
				(sheetname "")
			)
			(fill
				(thermal_gap 0.5)
				(thermal_bridge_width 0.5)
				(island_removal_mode 0)
			)
			(polygon
				(pts
					(xy 4.56946 -132.74802) (xy 4.06146 -132.74802) (xy 4.06146 -133.12902) (xy 4.56946 -133.12902)
				)
			)
		)
	)
	(footprint ""
		(layer "F.Cu")
		(at 20.5232 -97.310956 180)
		(property "Reference" "C1C11"
			(at 0 0 180)
			(layer "F.SilkS")
			(hide yes)
			(effects
				(font
					(size 1.27 1.27)
				)
			)
		)
		(property "Value" ""
			(at 0 0 180)
			(layer "F.Fab")
			(effects
				(font
					(size 1.27 1.27)
				)
			)
		)
		(duplicate_pad_numbers_are_jumpers no)
		(fp_rect
			(start 0.3048 -0.1016)
			(end -0.3048 0.9906)
			(stroke
				(width 0)
				(type default)
			)
			(fill no)
			(layer "F.CrtYd")
		)
		(fp_line
			(start 0.3048 0.9906)
			(end 0.3048 -0.1016)
			(stroke
				(width 0.1)
				(type default)
			)
			(layer "F.Fab")
		)
		(fp_line
			(start 0.3048 -0.1016)
			(end -0.3048 -0.1016)
			(stroke
				(width 0.1)
				(type default)
			)
			(layer "F.Fab")
		)
		(fp_line
			(start -0.3048 0.9906)
			(end 0.3048 0.9906)
			(stroke
				(width 0.1)
				(type default)
			)
			(layer "F.Fab")
		)
		(fp_line
			(start -0.3048 -0.1016)
			(end -0.3048 0.9906)
			(stroke
				(width 0.1)
				(type default)
			)
			(layer "F.Fab")
		)
		(pad "1" smd rect
			(at 0 0 180)
			(size 0.508 0.508)
			(layers "F.Cu" "F.Mask" "F.Paste")
			(net "A_TSENSE_PVSA_CPU1")
		)
		(pad "2" smd rect
			(at 0 0.889 180)
			(size 0.508 0.508)
			(layers "F.Cu" "F.Mask" "F.Paste")
			(net "GND")
		)
		(zone
			(layer "F.Cu")
			(hatch none 0.5)
			(connect_pads
				(clearance 0)
			)
			(min_thickness 0.25)
			(keepout
				(tracks allowed)
				(vias not_allowed)
				(pads allowed)
				(copperpour not_allowed)
				(footprints allowed)
			)
			(placement
				(enabled no)
				(sheetname "")
			)
			(fill
				(thermal_gap 0.5)
				(thermal_bridge_width 0.5)
				(island_removal_mode 0)
			)
			(polygon
				(pts
					(xy 20.2692 -97.564956) (xy 20.7772 -97.564956) (xy 20.7772 -97.945956) (xy 20.2692 -97.945956)
				)
			)
		)
		(zone
			(layer "F.Cu")
			(hatch none 0.5)
			(connect_pads
				(clearance 0)
			)
			(min_thickness 0.25)
			(keepout
				(tracks not_allowed)
				(vias allowed)
				(pads allowed)
				(copperpour not_allowed)
				(footprints allowed)
			)
			(placement
				(enabled no)
				(sheetname "")
			)
			(fill
				(thermal_gap 0.5)
				(thermal_bridge_width 0.5)
				(island_removal_mode 0)
			)
			(polygon
				(pts
					(xy 20.2692 -97.564956) (xy 20.7772 -97.564956) (xy 20.7772 -97.945956) (xy 20.2692 -97.945956)
				)
			)
		)
	)
	(footprint ""
		(layer "F.Cu")
		(at 332.172818 -129.921)
		(property "Reference" "C6B3"
			(at 0 0 0)
			(layer "F.SilkS")
			(hide yes)
			(effects
				(font
					(size 1.27 1.27)
				)
			)
		)
		(property "Value" ""
			(at 0 0 0)
			(layer "F.Fab")
			(effects
				(font
					(size 1.27 1.27)
				)
			)
		)
		(duplicate_pad_numbers_are_jumpers no)
		(fp_poly
			(pts
				(xy -0.7239 -0.2159) (xy 0.7239 -0.2159) (xy 0.7239 1.9939) (xy -0.7239 1.9939)
			)
			(stroke
				(width 0)
				(type default)
			)
			(fill no)
			(layer "F.CrtYd")
		)
		(fp_line
			(start -0.7239 -0.2159)
			(end -0.7239 1.9939)
			(stroke
				(width 0.1)
				(type default)
			)
			(layer "F.Fab")
		)
		(fp_line
			(start -0.7239 1.9939)
			(end 0.7239 1.9939)
			(stroke
				(width 0.1)
				(type default)
			)
			(layer "F.Fab")
		)
		(fp_line
			(start 0.7239 -0.2159)
			(end -0.7239 -0.2159)
			(stroke
				(width 0.1)
				(type default)
			)
			(layer "F.Fab")
		)
		(fp_line
			(start 0.7239 1.9939)
			(end 0.7239 -0.2159)
			(stroke
				(width 0.1)
				(type default)
			)
			(layer "F.Fab")
		)
		(pad "1" smd rect
			(at 0 0)
			(size 1.27 1.016)
			(layers "F.Cu" "F.Mask" "F.Paste")
			(net "PVPP_DEF")
		)
		(pad "2" smd rect
			(at 0 1.778)
			(size 1.27 1.016)
			(layers "F.Cu" "F.Mask" "F.Paste")
			(net "GND")
		)
		(zone
			(layer "F.Cu")
			(hatch none 0.5)
			(connect_pads
				(clearance 0)
			)
			(min_thickness 0.25)
			(keepout
				(tracks not_allowed)
				(vias allowed)
				(pads allowed)
				(copperpour not_allowed)
				(footprints allowed)
			)
			(placement
				(enabled no)
				(sheetname "")
			)
			(fill
				(thermal_gap 0.5)
				(thermal_bridge_width 0.5)
				(island_removal_mode 0)
			)
			(polygon
				(pts
					(xy 331.537818 -129.413) (xy 332.807818 -129.413) (xy 332.807818 -128.651) (xy 331.537818 -128.651)
				)
			)
		)
	)
)
